(kicad_pcb
	(version 20241229)
	(generator "pcbnew")
	(generator_version "9.0")
	(general
		(thickness 1.61)
		(legacy_teardrops no)
	)
	(paper "A3")
	(title_block
		(title "RDIMM DDR5 Tester")
		(date "2026-05-21")
		(rev "2.2.0")
		(company "Antmicro")
		(comment 9 "footprints 518-522 of 796")
	)
	(layers
		(0 "F.Cu" signal)
		(4 "In1.Cu" power)
		(6 "In2.Cu" mixed)
		(8 "In3.Cu" power)
		(10 "In4.Cu" mixed)
		(12 "In5.Cu" power)
		(14 "In6.Cu" mixed)
		(16 "In7.Cu" power)
		(18 "In8.Cu" power)
		(20 "In9.Cu" mixed)
		(22 "In10.Cu" power)
		(2 "B.Cu" signal)
		(9 "F.Adhes" user "F.Adhesive")
		(11 "B.Adhes" user "B.Adhesive")
		(13 "F.Paste" user)
		(15 "B.Paste" user)
		(5 "F.SilkS" user "F.Silkscreen")
		(7 "B.SilkS" user "B.Silkscreen")
		(1 "F.Mask" user)
		(3 "B.Mask" user)
		(17 "Dwgs.User" user "User.Drawings")
		(19 "Cmts.User" user "User.Comments")
		(21 "Eco1.User" user "User.Eco1")
		(23 "Eco2.User" user "User.Eco2")
		(25 "Edge.Cuts" user)
		(27 "Margin" user)
		(31 "F.CrtYd" user "F.Courtyard")
		(29 "B.CrtYd" user "B.Courtyard")
		(35 "F.Fab" user)
		(33 "B.Fab" user)
	)
	(footprint "antmicro-footprints:R_0402_1005Metric"
		(layer "B.Cu")
		(at 231.685 182.995)
		(descr "Resistor SMD 0402")
		(tags "resistor SMD 0402")
		(property "Reference" "R195"
			(at -1.815 -1.555 0)
			(layer "B.SilkS")
			(effects
				(font
					(size 0.7 0.7)
					(thickness 0.15)
				)
				(justify right bottom mirror)
			)
		)
		(property "Value" "R_60k4_0402"
			(at -1.011843 -1.772047 0)
			(layer "B.Fab")
			(effects
				(font
					(size 0.7 0.7)
					(thickness 0.15)
				)
				(justify right bottom mirror)
			)
		)
		(property "Datasheet" "https://www.bourns.com/docs/product-datasheets/cr.pdf"
			(at 0 0 0)
			(layer "F.Fab")
			(hide yes)
			(effects
				(font
					(size 1.27 1.27)
					(thickness 0.15)
				)
			)
		)
		(property "MPN" "CR0402-FX-6042GLF"
			(at 0 0 0)
			(unlocked yes)
			(layer "B.Fab")
			(hide yes)
			(effects
				(font
					(size 1 1)
					(thickness 0.15)
				)
				(justify mirror)
			)
		)
		(property "Manufacturer" "Bourns"
			(at 0 0 0)
			(unlocked yes)
			(layer "B.Fab")
			(hide yes)
			(effects
				(font
					(size 1 1)
					(thickness 0.15)
				)
				(justify mirror)
			)
		)
		(property "License" "Apache-2.0"
			(at 0 0 0)
			(unlocked yes)
			(layer "B.Fab")
			(hide yes)
			(effects
				(font
					(size 1 1)
					(thickness 0.15)
				)
				(justify mirror)
			)
		)
		(property "Author" "Antmicro"
			(at 0 0 0)
			(unlocked yes)
			(layer "B.Fab")
			(hide yes)
			(effects
				(font
					(size 1 1)
					(thickness 0.15)
				)
				(justify mirror)
			)
		)
		(property "Val" "60k4"
			(at 0 0 0)
			(unlocked yes)
			(layer "B.Fab")
			(hide yes)
			(effects
				(font
					(size 1 1)
					(thickness 0.15)
				)
				(justify mirror)
			)
		)
		(property "Tolerance" "1%"
			(at 0 0 0)
			(unlocked yes)
			(layer "B.Fab")
			(hide yes)
			(effects
				(font
					(size 1 1)
					(thickness 0.15)
				)
				(justify mirror)
			)
		)
		(sheetname "/Supply/DC-DC VCCINT/")
		(sheetfile "dc-dc-vccint.kicad_sch")
		(attr smd)
		(fp_rect
			(start -0.925 0.47)
			(end 0.925 -0.47)
			(stroke
				(width 0.05)
				(type default)
			)
			(fill no)
			(layer "B.CrtYd")
		)
		(fp_rect
			(start -0.5 0.25)
			(end 0.5 -0.25)
			(stroke
				(width 0.15)
				(type solid)
			)
			(fill no)
			(layer "B.Fab")
		)
		(fp_text user "${REFERENCE}"
			(at -0.95 -3.168 180)
			(layer "B.Fab")
			(effects
				(font
					(size 0.7 0.7)
					(thickness 0.15)
				)
				(justify left bottom mirror)
			)
		)
		(fp_text user "License: Apache-2.0"
			(at -0.95 -5.169 180)
			(layer "B.Fab")
			(effects
				(font
					(size 0.7 0.7)
					(thickness 0.15)
				)
				(justify left bottom mirror)
			)
		)
		(fp_text user "Author: Antmicro"
			(at -0.95 -4.169 180)
			(layer "B.Fab")
			(effects
				(font
					(size 0.7 0.7)
					(thickness 0.15)
				)
				(justify left bottom mirror)
			)
		)
		(pad "1" smd roundrect
			(at -0.48 0)
			(size 0.59 0.64)
			(layers "B.Cu" "B.Mask" "B.Paste")
			(roundrect_rratio 0.25)
			(net 1 "GND")
			(pintype "passive")
		)
		(pad "2" smd roundrect
			(at 0.48 0)
			(size 0.59 0.64)
			(layers "B.Cu" "B.Mask" "B.Paste")
			(roundrect_rratio 0.25)
			(net 726 "Net-(U36-I_{REF})")
			(pintype "passive")
		)
	)
	(footprint "antmicro-footprints:C_0402_1005Metric"
		(layer "B.Cu")
		(at 122.95 148.61)
		(descr "Capacitor SMD 0402")
		(tags "capacitor SMD 0402")
		(property "Reference" "C302"
			(at 2.4 0.872 0)
			(layer "B.SilkS")
			(effects
				(font
					(size 0.7 0.7)
					(thickness 0.15)
				)
				(justify right bottom mirror)
			)
		)
		(property "Value" "C_100n_0402"
			(at -1.022927 -2.155213 0)
			(layer "B.Fab")
			(effects
				(font
					(size 0.7 0.7)
					(thickness 0.15)
				)
				(justify right bottom mirror)
			)
		)
		(property "Datasheet" "https://www.murata.com/products/productdetail?partno=GRM155R61H104KE14%23"
			(at 0 0 0)
			(layer "F.Fab")
			(hide yes)
			(effects
				(font
					(size 1.27 1.27)
					(thickness 0.15)
				)
			)
		)
		(property "Manufacturer" "Murata"
			(at 0 0 0)
			(unlocked yes)
			(layer "B.Fab")
			(hide yes)
			(effects
				(font
					(size 1 1)
					(thickness 0.15)
				)
				(justify mirror)
			)
		)
		(property "MPN" "GRM155R61H104KE14D"
			(at 0 0 0)
			(unlocked yes)
			(layer "B.Fab")
			(hide yes)
			(effects
				(font
					(size 1 1)
					(thickness 0.15)
				)
				(justify mirror)
			)
		)
		(property "Val" "100n"
			(at 0 0 0)
			(unlocked yes)
			(layer "B.Fab")
			(hide yes)
			(effects
				(font
					(size 1 1)
					(thickness 0.15)
				)
				(justify mirror)
			)
		)
		(property "License" "Apache-2.0"
			(at 0 0 0)
			(unlocked yes)
			(layer "B.Fab")
			(hide yes)
			(effects
				(font
					(size 1 1)
					(thickness 0.15)
				)
				(justify mirror)
			)
		)
		(property "Author" "Antmicro"
			(at 0 0 0)
			(unlocked yes)
			(layer "B.Fab")
			(hide yes)
			(effects
				(font
					(size 1 1)
					(thickness 0.15)
				)
				(justify mirror)
			)
		)
		(property "Voltage" "50V"
			(at 0 0 0)
			(unlocked yes)
			(layer "B.Fab")
			(hide yes)
			(effects
				(font
					(size 1 1)
					(thickness 0.15)
				)
				(justify mirror)
			)
		)
		(property "Dielectric" "X5R"
			(at 0 0 0)
			(unlocked yes)
			(layer "B.Fab")
			(hide yes)
			(effects
				(font
					(size 1 1)
					(thickness 0.15)
				)
				(justify mirror)
			)
		)
		(sheetname "/FPGA MGT Interface/")
		(sheetfile "fpga-mgt.kicad_sch")
		(attr smd)
		(fp_rect
			(start -0.925 0.47)
			(end 0.925 -0.47)
			(stroke
				(width 0.05)
				(type default)
			)
			(fill no)
			(layer "B.CrtYd")
		)
		(fp_line
			(start -0.494 -0.248)
			(end -0.494 0.25)
			(stroke
				(width 0.15)
				(type solid)
			)
			(layer "B.Fab")
		)
		(fp_line
			(start -0.494 0.25)
			(end 0.504 0.25)
			(stroke
				(width 0.15)
				(type solid)
			)
			(layer "B.Fab")
		)
		(fp_line
			(start 0.504 -0.248)
			(end -0.494 -0.248)
			(stroke
				(width 0.15)
				(type solid)
			)
			(layer "B.Fab")
		)
		(fp_line
			(start 0.504 0.25)
			(end 0.504 -0.248)
			(stroke
				(width 0.15)
				(type solid)
			)
			(layer "B.Fab")
		)
		(fp_text user "Author: Antmicro"
			(at -0.939 -3.399 180)
			(layer "B.Fab")
			(effects
				(font
					(size 0.7 0.7)
					(thickness 0.15)
				)
				(justify left bottom mirror)
			)
		)
		(fp_text user "${REFERENCE}"
			(at -0.939 -4.599 180)
			(layer "B.Fab")
			(effects
				(font
					(size 0.7 0.7)
					(thickness 0.15)
				)
				(justify left bottom mirror)
			)
		)
		(fp_text user "License: Apache-2.0"
			(at -0.939 -5.799 180)
			(layer "B.Fab")
			(effects
				(font
					(size 0.7 0.7)
					(thickness 0.15)
				)
				(justify left bottom mirror)
			)
		)
		(pad "1" smd roundrect
			(at -0.48 0)
			(size 0.59 0.64)
			(layers "B.Cu" "B.Mask" "B.Paste")
			(roundrect_rratio 0.25)
			(net 342 "/FPGA MGT Interface/HDMI_IN.D2_N")
			(pintype "passive")
		)
		(pad "2" smd roundrect
			(at 0.48 0)
			(size 0.59 0.64)
			(layers "B.Cu" "B.Mask" "B.Paste")
			(roundrect_rratio 0.25)
			(net 648 "/FPGA MGT Interface/HDMI_FPGA.RX2_N")
			(pintype "passive")
		)
	)
	(footprint "antmicro-footprints:R_0402_1005Metric"
		(layer "B.Cu")
		(at 102.6 102.1 -90)
		(descr "Resistor SMD 0402")
		(tags "resistor SMD 0402")
		(property "Reference" "R46"
			(at -1.122484 0.772697 90)
			(layer "B.SilkS")
			(effects
				(font
					(size 0.7 0.7)
					(thickness 0.15)
				)
				(justify left bottom mirror)
			)
		)
		(property "Value" "R_330R_0402"
			(at -1.011843 -1.772047 90)
			(layer "B.Fab")
			(effects
				(font
					(size 0.7 0.7)
					(thickness 0.15)
				)
				(justify left bottom mirror)
			)
		)
		(property "Datasheet" "https://www.bourns.com/docs/product-datasheets/cr.pdf"
			(at 0 0 270)
			(layer "F.Fab")
			(hide yes)
			(effects
				(font
					(size 1.27 1.27)
					(thickness 0.15)
				)
			)
		)
		(property "Manufacturer" "Bourns"
			(at 0 0 270)
			(unlocked yes)
			(layer "B.Fab")
			(hide yes)
			(effects
				(font
					(size 1 1)
					(thickness 0.15)
				)
				(justify mirror)
			)
		)
		(property "MPN" "CR0402-FX-3300GLF"
			(at 0 0 270)
			(unlocked yes)
			(layer "B.Fab")
			(hide yes)
			(effects
				(font
					(size 1 1)
					(thickness 0.15)
				)
				(justify mirror)
			)
		)
		(property "Val" "330R"
			(at 0 0 270)
			(unlocked yes)
			(layer "B.Fab")
			(hide yes)
			(effects
				(font
					(size 1 1)
					(thickness 0.15)
				)
				(justify mirror)
			)
		)
		(property "License" "Apache-2.0"
			(at 0 0 270)
			(unlocked yes)
			(layer "B.Fab")
			(hide yes)
			(effects
				(font
					(size 1 1)
					(thickness 0.15)
				)
				(justify mirror)
			)
		)
		(property "Author" "Antmicro"
			(at 0 0 270)
			(unlocked yes)
			(layer "B.Fab")
			(hide yes)
			(effects
				(font
					(size 1 1)
					(thickness 0.15)
				)
				(justify mirror)
			)
		)
		(property "Tolerance" "1%"
			(at 0 0 270)
			(unlocked yes)
			(layer "B.Fab")
			(hide yes)
			(effects
				(font
					(size 1 1)
					(thickness 0.15)
				)
				(justify mirror)
			)
		)
		(sheetname "/FPGA banks HD/")
		(sheetfile "fpga-hd-banks.kicad_sch")
		(attr smd)
		(fp_rect
			(start -0.925 0.47)
			(end 0.925 -0.47)
			(stroke
				(width 0.05)
				(type default)
			)
			(fill no)
			(layer "B.CrtYd")
		)
		(fp_rect
			(start -0.5 0.25)
			(end 0.5 -0.25)
			(stroke
				(width 0.15)
				(type solid)
			)
			(fill no)
			(layer "B.Fab")
		)
		(fp_text user "License: Apache-2.0"
			(at -0.95 -5.169 90)
			(layer "B.Fab")
			(effects
				(font
					(size 0.7 0.7)
					(thickness 0.15)
				)
				(justify left bottom mirror)
			)
		)
		(fp_text user "${REFERENCE}"
			(at -0.95 -3.168 90)
			(layer "B.Fab")
			(effects
				(font
					(size 0.7 0.7)
					(thickness 0.15)
				)
				(justify left bottom mirror)
			)
		)
		(fp_text user "Author: Antmicro"
			(at -0.95 -4.169 90)
			(layer "B.Fab")
			(effects
				(font
					(size 0.7 0.7)
					(thickness 0.15)
				)
				(justify left bottom mirror)
			)
		)
		(pad "1" smd roundrect
			(at -0.48 0 270)
			(size 0.59 0.64)
			(layers "B.Cu" "B.Mask" "B.Paste")
			(roundrect_rratio 0.25)
			(net 233 "Net-(D8-A)")
			(pintype "passive")
		)
		(pad "2" smd roundrect
			(at 0.48 0 270)
			(size 0.59 0.64)
			(layers "B.Cu" "B.Mask" "B.Paste")
			(roundrect_rratio 0.25)
			(net 276 "Net-(Q8-D)")
			(pintype "passive")
		)
	)
	(footprint "antmicro-footprints:C_0402_1005Metric_EIA"
		(layer "B.Cu")
		(at 192 148.5 90)
		(descr "Capacitor SMD 0402 (1005 Metric), square (rectangular) end terminal, IPC_7351 nominal, (Body size source: IPC-SM-782 page 76, https://www.pcb-3d.com/wordpress/wp-content/uploads/ipc-sm-782a_amendment_1_and_2.pdf)")
		(tags "capacitor 0402")
		(property "Reference" "C57"
			(at 10.2 -30.65 90)
			(layer "B.SilkS")
			(effects
				(font
					(size 0.7 0.7)
					(thickness 0.15)
				)
				(justify right bottom mirror)
			)
		)
		(property "Value" "C_1u_25V_0402"
			(at 0 -1.169 90)
			(layer "B.Fab")
			(effects
				(font
					(size 0.7 0.7)
					(thickness 0.15)
				)
				(justify right bottom mirror)
			)
		)
		(property "Datasheet" "https://www.murata.com/products/productdetail?partno=GRM155R61E105KE11%23"
			(at 0 0 90)
			(layer "F.Fab")
			(hide yes)
			(effects
				(font
					(size 1.27 1.27)
					(thickness 0.15)
				)
			)
		)
		(property "MPN" "GRM155R61E105KE11J"
			(at 0 0 90)
			(unlocked yes)
			(layer "B.Fab")
			(hide yes)
			(effects
				(font
					(size 1 1)
					(thickness 0.15)
				)
				(justify mirror)
			)
		)
		(property "Manufacturer" "Murata"
			(at 0 0 90)
			(unlocked yes)
			(layer "B.Fab")
			(hide yes)
			(effects
				(font
					(size 1 1)
					(thickness 0.15)
				)
				(justify mirror)
			)
		)
		(property "License" "Apache-2.0"
			(at 0 0 90)
			(unlocked yes)
			(layer "B.Fab")
			(hide yes)
			(effects
				(font
					(size 1 1)
					(thickness 0.15)
				)
				(justify mirror)
			)
		)
		(property "Author" "Antmicro"
			(at 0 0 90)
			(unlocked yes)
			(layer "B.Fab")
			(hide yes)
			(effects
				(font
					(size 1 1)
					(thickness 0.15)
				)
				(justify mirror)
			)
		)
		(property "Val" "1u"
			(at 0 0 90)
			(unlocked yes)
			(layer "B.Fab")
			(hide yes)
			(effects
				(font
					(size 1 1)
					(thickness 0.15)
				)
				(justify mirror)
			)
		)
		(property "Voltage" "25V"
			(at 0 0 90)
			(unlocked yes)
			(layer "B.Fab")
			(hide yes)
			(effects
				(font
					(size 1 1)
					(thickness 0.15)
				)
				(justify mirror)
			)
		)
		(property "Dielectric" "X5R"
			(at 0 0 90)
			(unlocked yes)
			(layer "B.Fab")
			(hide yes)
			(effects
				(font
					(size 1 1)
					(thickness 0.15)
				)
				(justify mirror)
			)
		)
		(sheetname "/FPGA power/")
		(sheetfile "fpga-power.kicad_sch")
		(attr smd)
		(fp_rect
			(start -0.95 0.45)
			(end 0.95 -0.45)
			(stroke
				(width 0.05)
				(type default)
			)
			(fill no)
			(layer "B.CrtYd")
		)
		(fp_line
			(start 0.498 -0.248)
			(end -0.5 -0.248)
			(stroke
				(width 0.15)
				(type solid)
			)
			(layer "B.Fab")
		)
		(fp_line
			(start -0.5 -0.248)
			(end -0.5 0.25)
			(stroke
				(width 0.15)
				(type solid)
			)
			(layer "B.Fab")
		)
		(fp_line
			(start 0.498 0.25)
			(end 0.498 -0.248)
			(stroke
				(width 0.15)
				(type solid)
			)
			(layer "B.Fab")
		)
		(fp_line
			(start -0.5 0.25)
			(end 0.498 0.25)
			(stroke
				(width 0.15)
				(type solid)
			)
			(layer "B.Fab")
		)
		(fp_text user "License: Apache-2.0"
			(at -0.9656 -4.369 270)
			(layer "B.Fab")
			(effects
				(font
					(size 0.7 0.7)
					(thickness 0.15)
				)
				(justify left bottom mirror)
			)
		)
		(fp_text user "Author: Antmicro"
			(at -0.9656 -5.569 270)
			(layer "B.Fab")
			(effects
				(font
					(size 0.7 0.7)
					(thickness 0.15)
				)
				(justify left bottom mirror)
			)
		)
		(fp_text user "${REFERENCE}"
			(at -0.9656 -3.169 270)
			(layer "B.Fab")
			(effects
				(font
					(size 0.7 0.7)
					(thickness 0.15)
				)
				(justify left bottom mirror)
			)
		)
		(pad "1" smd roundrect
			(at -0.5 0)
			(size 0.6 0.6)
			(layers "B.Cu" "B.Mask" "B.Paste")
			(roundrect_rratio 0.25)
			(net 1 "GND")
			(pintype "passive")
		)
		(pad "2" smd roundrect
			(at 0.498 0 90)
			(size 0.6 0.6)
			(layers "B.Cu" "B.Mask" "B.Paste")
			(roundrect_rratio 0.25)
			(net 553 "+0V85")
			(pintype "passive")
		)
	)
	(footprint "antmicro-footprints:R_0402_1005Metric"
		(layer "B.Cu")
		(at 105.3 102.1 -90)
		(descr "Resistor SMD 0402")
		(tags "resistor SMD 0402")
		(property "Reference" "R45"
			(at -1.122484 0.772697 90)
			(layer "B.SilkS")
			(effects
				(font
					(size 0.7 0.7)
					(thickness 0.15)
				)
				(justify left bottom mirror)
			)
		)
		(property "Value" "R_330R_0402"
			(at -1.011843 -1.772047 90)
			(layer "B.Fab")
			(effects
				(font
					(size 0.7 0.7)
					(thickness 0.15)
				)
				(justify left bottom mirror)
			)
		)
		(property "Datasheet" "https://www.bourns.com/docs/product-datasheets/cr.pdf"
			(at 0 0 270)
			(layer "F.Fab")
			(hide yes)
			(effects
				(font
					(size 1.27 1.27)
					(thickness 0.15)
				)
			)
		)
		(property "Manufacturer" "Bourns"
			(at 0 0 270)
			(unlocked yes)
			(layer "B.Fab")
			(hide yes)
			(effects
				(font
					(size 1 1)
					(thickness 0.15)
				)
				(justify mirror)
			)
		)
		(property "MPN" "CR0402-FX-3300GLF"
			(at 0 0 270)
			(unlocked yes)
			(layer "B.Fab")
			(hide yes)
			(effects
				(font
					(size 1 1)
					(thickness 0.15)
				)
				(justify mirror)
			)
		)
		(property "Val" "330R"
			(at 0 0 270)
			(unlocked yes)
			(layer "B.Fab")
			(hide yes)
			(effects
				(font
					(size 1 1)
					(thickness 0.15)
				)
				(justify mirror)
			)
		)
		(property "License" "Apache-2.0"
			(at 0 0 270)
			(unlocked yes)
			(layer "B.Fab")
			(hide yes)
			(effects
				(font
					(size 1 1)
					(thickness 0.15)
				)
				(justify mirror)
			)
		)
		(property "Author" "Antmicro"
			(at 0 0 270)
			(unlocked yes)
			(layer "B.Fab")
			(hide yes)
			(effects
				(font
					(size 1 1)
					(thickness 0.15)
				)
				(justify mirror)
			)
		)
		(property "Tolerance" "1%"
			(at 0 0 270)
			(unlocked yes)
			(layer "B.Fab")
			(hide yes)
			(effects
				(font
					(size 1 1)
					(thickness 0.15)
				)
				(justify mirror)
			)
		)
		(sheetname "/FPGA banks HD/")
		(sheetfile "fpga-hd-banks.kicad_sch")
		(attr smd)
		(fp_rect
			(start -0.925 0.47)
			(end 0.925 -0.47)
			(stroke
				(width 0.05)
				(type default)
			)
			(fill no)
			(layer "B.CrtYd")
		)
		(fp_rect
			(start -0.5 0.25)
			(end 0.5 -0.25)
			(stroke
				(width 0.15)
				(type solid)
			)
			(fill no)
			(layer "B.Fab")
		)
		(fp_text user "${REFERENCE}"
			(at -0.95 -3.168 90)
			(layer "B.Fab")
			(effects
				(font
					(size 0.7 0.7)
					(thickness 0.15)
				)
				(justify left bottom mirror)
			)
		)
		(fp_text user "License: Apache-2.0"
			(at -0.95 -5.169 90)
			(layer "B.Fab")
			(effects
				(font
					(size 0.7 0.7)
					(thickness 0.15)
				)
				(justify left bottom mirror)
			)
		)
		(fp_text user "Author: Antmicro"
			(at -0.95 -4.169 90)
			(layer "B.Fab")
			(effects
				(font
					(size 0.7 0.7)
					(thickness 0.15)
				)
				(justify left bottom mirror)
			)
		)
		(pad "1" smd roundrect
			(at -0.48 0 270)
			(size 0.59 0.64)
			(layers "B.Cu" "B.Mask" "B.Paste")
			(roundrect_rratio 0.25)
			(net 232 "Net-(D7-A)")
			(pintype "passive")
		)
		(pad "2" smd roundrect
			(at 0.48 0 270)
			(size 0.59 0.64)
			(layers "B.Cu" "B.Mask" "B.Paste")
			(roundrect_rratio 0.25)
			(net 275 "Net-(Q7-D)")
			(pintype "passive")
		)
	)
)
